(kicad_pcb
	(version 20260206)
	(generator "pcbnew")
	(generator_version "10.0")
	(general
		(thickness 1.21888)
		(legacy_teardrops no)
	)
	(paper "A4")
	(title_block
		(title "timecard-v8 — TimeCard-DC-V8_EXP.PcbDoc")
		(comment 1 "Time Appliance Project (Time Card) / footprints 225-235 of 288")
	)
	(layers
		(0 "F.Cu" signal "TOP")
		(4 "In1.Cu" signal "SGND")
		(6 "In2.Cu" signal "IN1")
		(8 "In3.Cu" signal "IN2")
		(10 "In4.Cu" signal "SGND1")
		(2 "B.Cu" signal "BOTTOM")
		(9 "F.Adhes" user "F.Adhesive")
		(11 "B.Adhes" user "B.Adhesive")
		(13 "F.Paste" user "Top Paste")
		(15 "B.Paste" user "Bottom Paste")
		(5 "F.SilkS" user "Top Overlay")
		(7 "B.SilkS" user "Bottom Overlay")
		(1 "F.Mask" user "Top Solder")
		(3 "B.Mask" user "Bottom Solder")
		(17 "Dwgs.User" user "User.Drawings")
		(19 "Cmts.User" user "User.Comments")
		(21 "Eco1.User" user "User.Eco1")
		(23 "Eco2.User" user "User.Eco2")
		(25 "Edge.Cuts" user)
		(27 "Margin" user)
		(31 "F.CrtYd" user "Top Courtyard")
		(29 "B.CrtYd" user "Bottom Courtyard")
		(35 "F.Fab" user "Top Component Center")
		(33 "B.Fab" user "Bottom Component Center")
	)
	(footprint "Vault:CAPC1005X56X25NL10T15"
		(layer "F.Cu")
		(at 190.8261 87.0162 90)
		(property "Reference" "C67"
			(at 0.2286 1.326931 90)
			(unlocked yes)
			(layer "F.SilkS")
			(effects
				(font
					(size 0.762 0.762)
					(thickness 0.2286)
				)
			)
		)
		(property "Value" "0.1uF_0402"
			(at 2.06903 2.567191 90)
			(unlocked yes)
			(layer "F.SilkS")
			(hide yes)
			(effects
				(font
					(size 0.762 0.762)
					(thickness 0.2286)
				)
			)
		)
		(sheetname "GPS_IMU_SENSORS")
		(sheetfile "GPS_IMU_SENSORS.kicad_sch")
		(duplicate_pad_numbers_are_jumpers no)
		(pad "1" smd rect
			(at -0.44 0 180)
			(size 0.64 0.68)
			(layers "F.Cu" "F.Mask" "F.Paste")
			(net "GND")
		)
		(pad "2" smd rect
			(at 0.44 0 180)
			(size 0.64 0.68)
			(layers "F.Cu" "F.Mask" "F.Paste")
			(net "+3.3V")
		)
	)
	(footprint "Vault:RESC1005X40X25LL05T10"
		(layer "F.Cu")
		(at 125.1261 88.3162)
		(property "Reference" "R97"
			(at -1.7714 0.626931 0)
			(unlocked yes)
			(layer "F.SilkS")
			(effects
				(font
					(size 0.762 0.762)
					(thickness 0.2286)
				)
			)
		)
		(property "Value" "49.9_1%_0402"
			(at -2.579871 8.823665 270)
			(unlocked yes)
			(layer "F.SilkS")
			(hide yes)
			(effects
				(font
					(size 0.762 0.762)
					(thickness 0.2286)
				)
			)
		)
		(sheetname "USBUart_DipSelects")
		(sheetfile "USBUart_DipSelects.kicad_sch")
		(duplicate_pad_numbers_are_jumpers no)
		(pad "1" smd rect
			(at -0.375 0 90)
			(size 0.45 0.5)
			(layers "F.Cu" "F.Mask" "F.Paste")
			(net "FPGA_MAC_PPSDIFF_OUT")
		)
		(pad "2" smd rect
			(at 0.375 0 90)
			(size 0.45 0.5)
			(layers "F.Cu" "F.Mask" "F.Paste")
			(net "NetR97_2")
		)
	)
	(footprint "Vault:FP-0402-L_1_0_0_05-W_0_5-IPC_A"
		(layer "F.Cu")
		(at 202.8261 129.2162 180)
		(property "Reference" "C69"
			(at 3.1714 -3.426921 0)
			(unlocked yes)
			(layer "F.SilkS")
			(effects
				(font
					(size 0.762 0.762)
					(thickness 0.2286)
				)
			)
		)
		(property "Value" "1uF_16V_0402"
			(at -2.744951 8.290315 90)
			(unlocked yes)
			(layer "F.SilkS")
			(hide yes)
			(effects
				(font
					(size 0.762 0.762)
					(thickness 0.2286)
				)
			)
		)
		(sheetname "POWER")
		(sheetfile "POWER.kicad_sch")
		(duplicate_pad_numbers_are_jumpers no)
		(fp_line
			(start 0.83624 0.73624)
			(end -0.83624 0.73624)
			(stroke
				(width 0.2)
				(type solid)
			)
			(layer "F.SilkS")
		)
		(fp_line
			(start 0.83624 -0.73624)
			(end -0.83624 -0.73624)
			(stroke
				(width 0.2)
				(type solid)
			)
			(layer "F.SilkS")
		)
		(fp_line
			(start 1.03624 0.53624)
			(end -1.03624 0.53624)
			(stroke
				(width 0.2)
				(type solid)
			)
			(layer "F.CrtYd")
		)
		(fp_line
			(start 1.03624 -0.53624)
			(end 1.03624 0.53624)
			(stroke
				(width 0.2)
				(type solid)
			)
			(layer "F.CrtYd")
		)
		(fp_line
			(start 1.03624 -0.53624)
			(end -1.03624 -0.53624)
			(stroke
				(width 0.2)
				(type solid)
			)
			(layer "F.CrtYd")
		)
		(fp_line
			(start -1.03624 -0.53624)
			(end -1.03624 0.53624)
			(stroke
				(width 0.2)
				(type solid)
			)
			(layer "F.CrtYd")
		)
		(fp_line
			(start 1.03624 0.53624)
			(end -1.03624 0.53624)
			(stroke
				(width 0.2)
				(type solid)
			)
			(layer "F.Fab")
		)
		(fp_line
			(start 1.03624 -0.53624)
			(end 1.03624 0.53624)
			(stroke
				(width 0.2)
				(type solid)
			)
			(layer "F.Fab")
		)
		(fp_line
			(start 1.03624 -0.53624)
			(end -1.03624 -0.53624)
			(stroke
				(width 0.2)
				(type solid)
			)
			(layer "F.Fab")
		)
		(fp_line
			(start 0.5 0)
			(end -0.5 0)
			(stroke
				(width 0.1)
				(type solid)
			)
			(layer "F.Fab")
		)
		(fp_line
			(start 0 -0.5)
			(end 0 0.5)
			(stroke
				(width 0.1)
				(type solid)
			)
			(layer "F.Fab")
		)
		(fp_line
			(start -1.03624 -0.53624)
			(end -1.03624 0.53624)
			(stroke
				(width 0.2)
				(type solid)
			)
			(layer "F.Fab")
		)
		(fp_text user "${REFERENCE}"
			(at -0.00001 0.09601 180)
			(unlocked yes)
			(layer "F.Fab")
			(effects
				(font
					(face "Arial")
					(size 0.63 0.63)
					(thickness 0.1)
				)
				(justify left bottom)
			)
		)
		(pad "1" smd rect
			(at -0.47856 0 180)
			(size 0.71535 0.67248)
			(layers "F.Cu" "F.Mask" "F.Paste")
			(net "P3V3_VDD")
			(solder_mask_margin 0)
			(solder_paste_margin 0)
		)
		(pad "2" smd rect
			(at 0.47856 0 180)
			(size 0.71535 0.67248)
			(layers "F.Cu" "F.Mask" "F.Paste")
			(net "GND")
			(solder_mask_margin 0)
			(solder_paste_margin 0)
		)
	)
	(footprint "Vault:AMPH-901-143-6RFX_V"
		(layer "F.Cu")
		(at 60.9761 108.5782 180)
		(property "Reference" "AN2"
			(at -5.917345 2.55101 90)
			(unlocked yes)
			(layer "F.SilkS")
			(effects
				(font
					(size 0.762 0.762)
					(thickness 0.2286)
				)
				(justify left bottom)
			)
		)
		(property "Value" "RF2-49B-T-00-50-G-HDW"
			(at 4.6101 -1.960245 0)
			(unlocked yes)
			(layer "F.SilkS")
			(hide yes)
			(effects
				(font
					(size 0.762 0.762)
					(thickness 0.2286)
				)
				(justify left bottom)
			)
		)
		(sheetname "USER_IO")
		(sheetfile "USER_IO.kicad_sch")
		(duplicate_pad_numbers_are_jumpers no)
		(fp_line
			(start 3.5 -1.38)
			(end 3.5 1.38)
			(stroke
				(width 0.2)
				(type solid)
			)
			(layer "F.SilkS")
		)
		(fp_line
			(start 1.38 3.5)
			(end -1.38 3.5)
			(stroke
				(width 0.2)
				(type solid)
			)
			(layer "F.SilkS")
		)
		(fp_line
			(start 1.38 -3.5)
			(end -1.38 -3.5)
			(stroke
				(width 0.2)
				(type solid)
			)
			(layer "F.SilkS")
		)
		(fp_line
			(start -3.5 -1.38)
			(end -3.5 1.38)
			(stroke
				(width 0.2)
				(type solid)
			)
			(layer "F.SilkS")
		)
		(pad "1" thru_hole rect
			(at 0 0 180)
			(size 2 2)
			(drill 1.5)
			(layers "*.Cu" "*.Mask")
			(remove_unused_layers no)
			(net "NetAN2_1")
		)
		(pad "2" thru_hole circle
			(at -2.54 -2.54 180)
			(size 2.2 2.2)
			(drill 1.7)
			(layers "*.Cu" "*.Mask")
			(remove_unused_layers no)
			(net "GND")
			(thermal_bridge_angle 90)
		)
		(pad "3" thru_hole circle
			(at -2.54 2.54 180)
			(size 2.2 2.2)
			(drill 1.7)
			(layers "*.Cu" "*.Mask")
			(remove_unused_layers no)
			(net "GND")
			(thermal_bridge_angle 90)
		)
		(pad "4" thru_hole circle
			(at 2.54 2.54 180)
			(size 2.2 2.2)
			(drill 1.7)
			(layers "*.Cu" "*.Mask")
			(remove_unused_layers no)
			(net "GND")
			(thermal_bridge_angle 90)
		)
		(pad "5" thru_hole circle
			(at 2.54 -2.54 180)
			(size 2.2 2.2)
			(drill 1.7)
			(layers "*.Cu" "*.Mask")
			(remove_unused_layers no)
			(net "GND")
			(thermal_bridge_angle 90)
		)
	)
	(footprint "Vault:SMTC-TSW-105-05-X-S"
		(layer "F.Cu")
		(at 109.2261 85.6162 180)
		(property "Reference" "P1"
			(at 13.073079 0.228605 90)
			(unlocked yes)
			(layer "F.SilkS")
			(effects
				(font
					(size 0.762 0.762)
					(thickness 0.2286)
				)
			)
		)
		(property "Value" "TSW-105-05-L-S"
			(at -2.910071 6.360355 90)
			(unlocked yes)
			(layer "F.SilkS")
			(hide yes)
			(effects
				(font
					(size 0.762 0.762)
					(thickness 0.2286)
				)
			)
		)
		(sheetname "GPS_IMU_SENSORS")
		(sheetfile "GPS_IMU_SENSORS.kicad_sch")
		(duplicate_pad_numbers_are_jumpers no)
		(fp_line
			(start 11.62 1.27)
			(end -1.46 1.27)
			(stroke
				(width 0.2)
				(type solid)
			)
			(layer "F.SilkS")
		)
		(fp_line
			(start 11.62 -1.27)
			(end 11.62 1.27)
			(stroke
				(width 0.2)
				(type solid)
			)
			(layer "F.SilkS")
		)
		(fp_line
			(start 11.62 -1.27)
			(end -1.46 -1.27)
			(stroke
				(width 0.2)
				(type solid)
			)
			(layer "F.SilkS")
		)
		(fp_line
			(start -1.46 -1.27)
			(end -1.46 1.27)
			(stroke
				(width 0.2)
				(type solid)
			)
			(layer "F.SilkS")
		)
		(pad "1" thru_hole rect
			(at 0 0 180)
			(size 1.55 1.55)
			(drill 1.02)
			(layers "*.Cu" "*.Mask")
			(remove_unused_layers no)
			(net "+3.3V")
		)
		(pad "2" thru_hole circle
			(at 2.54 0 180)
			(size 1.55 1.55)
			(drill 1.02)
			(layers "*.Cu" "*.Mask")
			(remove_unused_layers no)
			(net "GND")
			(thermal_bridge_angle 90)
		)
		(pad "3" thru_hole circle
			(at 5.08 0 180)
			(size 1.55 1.55)
			(drill 1.02)
			(layers "*.Cu" "*.Mask")
			(remove_unused_layers no)
			(net "SCL")
			(thermal_bridge_angle 90)
		)
		(pad "4" thru_hole circle
			(at 7.62 0 180)
			(size 1.55 1.55)
			(drill 1.02)
			(layers "*.Cu" "*.Mask")
			(remove_unused_layers no)
			(net "SDA")
			(thermal_bridge_angle 90)
		)
		(pad "5" thru_hole circle
			(at 10.16 0 180)
			(size 1.55 1.55)
			(drill 1.02)
			(layers "*.Cu" "*.Mask")
			(remove_unused_layers no)
			(net "NetP1_5")
			(thermal_bridge_angle 90)
		)
	)
	(footprint "Vault:FP-0402-L_1_0_1-W_0_5_0_1-IPC_C"
		(layer "F.Cu")
		(at 222.5261 78.8162)
		(property "Reference" "C94"
			(at 2.3286 0.126931 0)
			(unlocked yes)
			(layer "F.SilkS")
			(effects
				(font
					(size 0.762 0.762)
					(thickness 0.2286)
				)
			)
		)
		(property "Value" "0.1uF_25V_0402"
			(at -2.465551 9.839215 270)
			(unlocked yes)
			(layer "F.SilkS")
			(hide yes)
			(effects
				(font
					(size 0.762 0.762)
					(thickness 0.2286)
				)
			)
		)
		(sheetname "USBUart_DipSelects")
		(sheetfile "USBUart_DipSelects.kicad_sch")
		(duplicate_pad_numbers_are_jumpers no)
		(fp_line
			(start -0.65607 -0.7)
			(end 0.65607 -0.7)
			(stroke
				(width 0.2)
				(type solid)
			)
			(layer "F.SilkS")
		)
		(fp_line
			(start -0.65607 0.7)
			(end 0.65607 0.7)
			(stroke
				(width 0.2)
				(type solid)
			)
			(layer "F.SilkS")
		)
		(fp_line
			(start -0.75607 -0.4)
			(end 0.75607 -0.4)
			(stroke
				(width 0.2)
				(type solid)
			)
			(layer "F.CrtYd")
		)
		(fp_line
			(start -0.75607 0.4)
			(end -0.75607 -0.4)
			(stroke
				(width 0.2)
				(type solid)
			)
			(layer "F.CrtYd")
		)
		(fp_line
			(start -0.75607 0.4)
			(end 0.75607 0.4)
			(stroke
				(width 0.2)
				(type solid)
			)
			(layer "F.CrtYd")
		)
		(fp_line
			(start 0.75607 0.4)
			(end 0.75607 -0.4)
			(stroke
				(width 0.2)
				(type solid)
			)
			(layer "F.CrtYd")
		)
		(fp_line
			(start -0.75607 -0.4)
			(end 0.75607 -0.4)
			(stroke
				(width 0.2)
				(type solid)
			)
			(layer "F.Fab")
		)
		(fp_line
			(start -0.75607 0.4)
			(end -0.75607 -0.4)
			(stroke
				(width 0.2)
				(type solid)
			)
			(layer "F.Fab")
		)
		(fp_line
			(start -0.75607 0.4)
			(end 0.75607 0.4)
			(stroke
				(width 0.2)
				(type solid)
			)
			(layer "F.Fab")
		)
		(fp_line
			(start -0.5 0)
			(end 0.5 0)
			(stroke
				(width 0.1)
				(type solid)
			)
			(layer "F.Fab")
		)
		(fp_line
			(start 0 0.5)
			(end 0 -0.5)
			(stroke
				(width 0.1)
				(type solid)
			)
			(layer "F.Fab")
		)
		(fp_line
			(start 0.75607 0.4)
			(end 0.75607 -0.4)
			(stroke
				(width 0.2)
				(type solid)
			)
			(layer "F.Fab")
		)
		(fp_text user "${REFERENCE}"
			(at -0.00001 0.09602 360)
			(unlocked yes)
			(layer "F.Fab")
			(effects
				(font
					(face "Arial")
					(size 0.63 0.63)
					(thickness 0.1)
				)
				(justify left bottom)
			)
		)
		(pad "1" smd rect
			(at -0.36554 0)
			(size 0.58106 0.51213)
			(layers "F.Cu" "F.Mask" "F.Paste")
			(net "+3.3V")
			(solder_mask_margin 0)
			(solder_paste_margin 0)
		)
		(pad "2" smd rect
			(at 0.36554 0)
			(size 0.58106 0.51213)
			(layers "F.Cu" "F.Mask" "F.Paste")
			(net "GND")
			(solder_mask_margin 0)
			(solder_paste_margin 0)
		)
	)
	(footprint "Vault:FP-CC0603-DA-MFG"
		(layer "F.Cu")
		(at 215.6261 130.2162 180)
		(property "Reference" "C68"
			(at 0.0286 -1.573069 180)
			(unlocked yes)
			(layer "F.SilkS")
			(effects
				(font
					(size 0.762 0.762)
					(thickness 0.2286)
				)
			)
		)
		(property "Value" "0.1uF_50V_0603"
			(at -3.075151 9.686815 90)
			(unlocked yes)
			(layer "F.SilkS")
			(hide yes)
			(effects
				(font
					(size 0.762 0.762)
					(thickness 0.2286)
				)
			)
		)
		(sheetname "POWER")
		(sheetfile "POWER.kicad_sch")
		(duplicate_pad_numbers_are_jumpers no)
		(fp_line
			(start 0.85 0.85)
			(end -0.85 0.85)
			(stroke
				(width 0.2)
				(type solid)
			)
			(layer "F.SilkS")
		)
		(fp_line
			(start 0.85 -0.85)
			(end -0.85 -0.85)
			(stroke
				(width 0.2)
				(type solid)
			)
			(layer "F.SilkS")
		)
		(fp_line
			(start 1.35 0.75)
			(end -1.35 0.75)
			(stroke
				(width 0.2)
				(type solid)
			)
			(layer "F.CrtYd")
		)
		(fp_line
			(start 1.35 -0.75)
			(end 1.35 0.75)
			(stroke
				(width 0.2)
				(type solid)
			)
			(layer "F.CrtYd")
		)
		(fp_line
			(start 1.35 -0.75)
			(end -1.35 -0.75)
			(stroke
				(width 0.2)
				(type solid)
			)
			(layer "F.CrtYd")
		)
		(fp_line
			(start -1.35 -0.75)
			(end -1.35 0.75)
			(stroke
				(width 0.2)
				(type solid)
			)
			(layer "F.CrtYd")
		)
		(fp_line
			(start 1.35 0.75)
			(end -1.35 0.75)
			(stroke
				(width 0.2)
				(type solid)
			)
			(layer "F.Fab")
		)
		(fp_line
			(start 1.35 -0.75)
			(end 1.35 0.75)
			(stroke
				(width 0.2)
				(type solid)
			)
			(layer "F.Fab")
		)
		(fp_line
			(start 1.35 -0.75)
			(end -1.35 -0.75)
			(stroke
				(width 0.2)
				(type solid)
			)
			(layer "F.Fab")
		)
		(fp_line
			(start 0.5 0)
			(end -0.5 0)
			(stroke
				(width 0.1)
				(type solid)
			)
			(layer "F.Fab")
		)
		(fp_line
			(start 0 -0.5)
			(end 0 0.5)
			(stroke
				(width 0.1)
				(type solid)
			)
			(layer "F.Fab")
		)
		(fp_line
			(start -1.35 -0.75)
			(end -1.35 0.75)
			(stroke
				(width 0.2)
				(type solid)
			)
			(layer "F.Fab")
		)
		(fp_text user "${REFERENCE}"
			(at -0.00001 0.09602 180)
			(unlocked yes)
			(layer "F.Fab")
			(effects
				(font
					(face "Arial")
					(size 0.63 0.63)
					(thickness 0.1)
				)
				(justify left bottom)
			)
		)
		(pad "1" smd rect
			(at -0.75 0 180)
			(size 0.8 0.9)
			(layers "F.Cu" "F.Mask" "F.Paste")
			(net "NetC68_1")
			(solder_mask_margin 0)
			(solder_paste_margin 0)
		)
		(pad "2" smd rect
			(at 0.75 0 180)
			(size 0.8 0.9)
			(layers "F.Cu" "F.Mask" "F.Paste")
			(net "NetC68_2")
			(solder_mask_margin 0)
			(solder_paste_margin 0)
		)
	)
	(footprint "Vault:RESC0402(1005)_N"
		(layer "F.Cu")
		(at 219.8261 116.0162)
		(property "Reference" "R4"
			(at -0.6 1.793345 0)
			(unlocked yes)
			(layer "F.SilkS")
			(effects
				(font
					(size 0.762 0.762)
					(thickness 0.2286)
				)
				(justify left bottom)
			)
		)
		(property "Value" "1.21_1%_0402"
			(at -0.2227 -8.970755 0)
			(unlocked yes)
			(layer "F.SilkS")
			(hide yes)
			(effects
				(font
					(size 0.762 0.762)
					(thickness 0.2286)
				)
				(justify left bottom)
			)
		)
		(sheetname "POWER")
		(sheetfile "POWER.kicad_sch")
		(duplicate_pad_numbers_are_jumpers no)
		(pad "1" smd rect
			(at -0.5 0 90)
			(size 0.65 0.55)
			(layers "F.Cu" "F.Mask" "F.Paste")
			(net "NetR4_1")
		)
		(pad "2" smd rect
			(at 0.5 0 90)
			(size 0.65 0.55)
			(layers "F.Cu" "F.Mask" "F.Paste")
			(net "NetC3_1")
		)
	)
	(footprint "Vault:RESC1608X55X30NL15T15"
		(layer "F.Cu")
		(at 84.1261 139.6162 -90)
		(property "Reference" "R31"
			(at 2.771395 -0.026931 90)
			(unlocked yes)
			(layer "F.SilkS")
			(effects
				(font
					(size 0.762 0.762)
					(thickness 0.2286)
				)
			)
		)
		(property "Value" "4.7K"
			(at 1.61204 2.325871 270)
			(unlocked yes)
			(layer "F.SilkS")
			(hide yes)
			(effects
				(font
					(size 0.762 0.762)
					(thickness 0.2286)
				)
			)
		)
		(sheetname "USER_IO")
		(sheetfile "USER_IO.kicad_sch")
		(duplicate_pad_numbers_are_jumpers no)
		(pad "1" smd rect
			(at -0.75 0)
			(size 0.95 0.95)
			(layers "F.Cu" "F.Mask" "F.Paste")
			(net "ANT4_IO_OUT")
		)
		(pad "2" smd rect
			(at 0.75 0)
			(size 0.95 0.95)
			(layers "F.Cu" "F.Mask" "F.Paste")
			(net "+3.3V")
		)
	)
	(footprint "Vault:CAPC1005X56X25NL10T15"
		(layer "F.Cu")
		(at 231.9261 127.0162 180)
		(property "Reference" "C84"
			(at -2.7286 -0.226931 0)
			(unlocked yes)
			(layer "F.SilkS")
			(effects
				(font
					(size 0.762 0.762)
					(thickness 0.2286)
				)
			)
		)
		(property "Value" "0.1uF_0402"
			(at -2.592551 7.0716 90)
			(unlocked yes)
			(layer "F.SilkS")
			(hide yes)
			(effects
				(font
					(size 0.762 0.762)
					(thickness 0.2286)
				)
			)
		)
		(sheetname "POWER")
		(sheetfile "POWER.kicad_sch")
		(duplicate_pad_numbers_are_jumpers no)
		(pad "1" smd rect
			(at -0.44 0 270)
			(size 0.64 0.68)
			(layers "F.Cu" "F.Mask" "F.Paste")
			(net "GND")
		)
		(pad "2" smd rect
			(at 0.44 0 270)
			(size 0.64 0.68)
			(layers "F.Cu" "F.Mask" "F.Paste")
			(net "+3.3V")
		)
	)
	(footprint "Vault:CAPC1608X87X45ML20T05"
		(layer "F.Cu")
		(at 80.6261 112.1162 -90)
		(property "Reference" "C28"
			(at 2.7714 -0.026931 90)
			(unlocked yes)
			(layer "F.SilkS")
			(effects
				(font
					(size 0.762 0.762)
					(thickness 0.2286)
				)
			)
		)
		(property "Value" "0.1uF"
			(at 2.069025 2.630671 270)
			(unlocked yes)
			(layer "F.SilkS")
			(hide yes)
			(effects
				(font
					(size 0.762 0.762)
					(thickness 0.2286)
				)
			)
		)
		(sheetname "USER_IO")
		(sheetfile "USER_IO.kicad_sch")
		(duplicate_pad_numbers_are_jumpers no)
		(pad "1" smd rect
			(at -0.7 0)
			(size 1.1 1.05)
			(layers "F.Cu" "F.Mask" "F.Paste")
			(net "+3.3V")
		)
		(pad "2" smd rect
			(at 0.7 0)
			(size 1.1 1.05)
			(layers "F.Cu" "F.Mask" "F.Paste")
			(net "GND")
		)
	)
)
